# T6G (Grand Teton) — schematic netlist excerpt (pin names and nets, part order shuffled) for the footprints in the layout excerpt that follows; sources: Cadence DE-HDL packaged netlist, KiCad conversion of 04192023_DAF0TMB3IC0_F0TG_MB_C_brd_V02_OCP.brd

C1995  Q_CAP_DIFFBUS  DIFF BUS_0.22UF 6.3V 20% X6S  pkg C0201  page 67 : \1\ = P3E_CPU0_P4_TX_C_DP<0> ; \2\ = P3E_CPU0_P4_TX_DP<0>
PC400  Q_CAP  2.2UF 10V 10% X6S  pkg C0402  page 219 : A = PVDDCR_CPU1_P1_VCC3 ; B = GND
PR3821  Q_RES  30.1K 1% CHIP  pkg 0402LF  page 140 : A = P12V_OCP_CB_2 ; B = GND

(kicad_pcb
	(version 20260206)
	(generator "pcbnew")
	(generator_version "10.0")
	(general
		(thickness 1.6)
		(legacy_teardrops no)
	)
	(paper "A4")
	(title_block
		(title "04192023_DAF0TMB3IC0_F0TG_MB_C_brd_V02_OCP.brd")
		(comment 1 "Grand Teton / footprints 461-463 of 8354")
	)
	(layers
		(0 "F.Cu" signal "TOP")
		(4 "In1.Cu" signal "GND")
		(6 "In2.Cu" signal "IN1")
		(8 "In3.Cu" signal "GND1")
		(10 "In4.Cu" signal "IN2")
		(12 "In5.Cu" signal "GND2")
		(14 "In6.Cu" signal "IN3")
		(16 "In7.Cu" signal "GND3")
		(18 "In8.Cu" signal "VCC")
		(20 "In9.Cu" signal "VCC1")
		(22 "In10.Cu" signal "GND4")
		(24 "In11.Cu" signal "IN4")
		(26 "In12.Cu" signal "GND5")
		(28 "In13.Cu" signal "IN5")
		(30 "In14.Cu" signal "GND6")
		(32 "In15.Cu" signal "IN6")
		(34 "In16.Cu" signal "GND7")
		(2 "B.Cu" signal "BOTTOM")
		(9 "F.Adhes" user "F.Adhesive")
		(11 "B.Adhes" user "B.Adhesive")
		(13 "F.Paste" user "Package Geometry/Pastemask Top")
		(15 "B.Paste" user "Package Geometry/Pastemask Bottom")
		(5 "F.SilkS" user "Ref Des/Silkscreen Top")
		(7 "B.SilkS" user "Ref Des/Silkscreen Bottom")
		(1 "F.Mask" user "Board Geometry/Soldermask Top")
		(3 "B.Mask" user "Board Geometry/Soldermask Bottom")
		(17 "Dwgs.User" user "User.Drawings")
		(19 "Cmts.User" user "User.Comments")
		(21 "Eco1.User" user "User.Eco1")
		(23 "Eco2.User" user "User.Eco2")
		(25 "Edge.Cuts" user "Board Geometry/Outline")
		(27 "Margin" user)
		(31 "F.CrtYd" user "Package Geometry/Place Bound Top")
		(29 "B.CrtYd" user "Package Geometry/Place Bound Bottom")
		(35 "F.Fab" user "Ref Des/Assembly Top")
		(33 "B.Fab" user "Ref Des/Assembly Bottom")
	)
	(footprint ""
		(layer "F.Cu")
		(at 239.152684 -52.01285)
		(property "Reference" "C1995"
			(at 0 0 0)
			(layer "F.SilkS")
			(hide yes)
			(effects
				(font
					(size 1.27 1.27)
				)
			)
		)
		(property "Value" ""
			(at 0 0 0)
			(layer "F.Fab")
			(effects
				(font
					(size 1.27 1.27)
				)
			)
		)
		(duplicate_pad_numbers_are_jumpers no)
		(fp_line
			(start -0.299974 -0.150114)
			(end 0.299974 -0.150114)
			(stroke
				(width 0.1)
				(type default)
			)
			(layer "F.Fab")
		)
		(fp_line
			(start -0.299974 0.150114)
			(end -0.299974 -0.150114)
			(stroke
				(width 0.1)
				(type default)
			)
			(layer "F.Fab")
		)
		(fp_line
			(start 0.299974 -0.150114)
			(end 0.299974 0.150114)
			(stroke
				(width 0.1)
				(type default)
			)
			(layer "F.Fab")
		)
		(fp_line
			(start 0.299974 0.150114)
			(end -0.299974 0.150114)
			(stroke
				(width 0.1)
				(type default)
			)
			(layer "F.Fab")
		)
		(pad "1" smd rect
			(at -0.2667 0)
			(size 0.3048 0.381)
			(layers "F.Cu" "F.Mask" "F.Paste")
			(net "P3E_CPU0_P4_TX_C_DP<0>")
		)
		(pad "2" smd rect
			(at 0.2667 0)
			(size 0.3048 0.381)
			(layers "F.Cu" "F.Mask" "F.Paste")
			(net "P3E_CPU0_P4_TX_DP<0>")
		)
	)
	(footprint ""
		(layer "F.Cu")
		(at 75.546458 -20.950682 180)
		(property "Reference" "PR3821"
			(at 0 0 180)
			(layer "F.SilkS")
			(hide yes)
			(effects
				(font
					(size 1.27 1.27)
				)
			)
		)
		(property "Value" ""
			(at 0 0 180)
			(layer "F.Fab")
			(effects
				(font
					(size 1.27 1.27)
				)
			)
		)
		(duplicate_pad_numbers_are_jumpers no)
		(fp_line
			(start 0.7874 0.4064)
			(end -0.7874 0.4064)
			(stroke
				(width 0.1524)
				(type default)
			)
			(layer "F.SilkS")
		)
		(fp_line
			(start 0.7874 -0.4064)
			(end 0.7874 0.4064)
			(stroke
				(width 0.1524)
				(type default)
			)
			(layer "F.SilkS")
		)
		(fp_line
			(start -0.7874 0.4064)
			(end -0.7874 -0.4064)
			(stroke
				(width 0.1524)
				(type default)
			)
			(layer "F.SilkS")
		)
		(fp_line
			(start -0.7874 -0.4064)
			(end 0.7874 -0.4064)
			(stroke
				(width 0.1524)
				(type default)
			)
			(layer "F.SilkS")
		)
		(fp_line
			(start 0.67945 0.3048)
			(end 0.120396 0.3048)
			(stroke
				(width 0.1)
				(type default)
			)
			(layer "F.Fab")
		)
		(fp_line
			(start 0.67945 -0.3048)
			(end 0.67945 0.3048)
			(stroke
				(width 0.1)
				(type default)
			)
			(layer "F.Fab")
		)
		(fp_line
			(start 0.12065 -0.2794)
			(end 0.12065 -0.3048)
			(stroke
				(width 0.1)
				(type default)
			)
			(layer "F.Fab")
		)
		(fp_line
			(start 0.12065 -0.3048)
			(end 0.67945 -0.3048)
			(stroke
				(width 0.1)
				(type default)
			)
			(layer "F.Fab")
		)
		(fp_line
			(start 0.120396 0.3048)
			(end 0.120396 0.2794)
			(stroke
				(width 0.1)
				(type default)
			)
			(layer "F.Fab")
		)
		(fp_line
			(start 0.120396 0.2794)
			(end -0.12065 0.2794)
			(stroke
				(width 0.1)
				(type default)
			)
			(layer "F.Fab")
		)
		(fp_line
			(start -0.12065 0.3048)
			(end -0.67945 0.3048)
			(stroke
				(width 0.1)
				(type default)
			)
			(layer "F.Fab")
		)
		(fp_line
			(start -0.12065 0.2794)
			(end -0.12065 0.3048)
			(stroke
				(width 0.1)
				(type default)
			)
			(layer "F.Fab")
		)
		(fp_line
			(start -0.12065 -0.2794)
			(end 0.12065 -0.2794)
			(stroke
				(width 0.1)
				(type default)
			)
			(layer "F.Fab")
		)
		(fp_line
			(start -0.12065 -0.305054)
			(end -0.12065 -0.2794)
			(stroke
				(width 0.1)
				(type default)
			)
			(layer "F.Fab")
		)
		(fp_line
			(start -0.67945 0.3048)
			(end -0.67945 -0.305054)
			(stroke
				(width 0.1)
				(type default)
			)
			(layer "F.Fab")
		)
		(fp_line
			(start -0.67945 -0.305054)
			(end -0.12065 -0.305054)
			(stroke
				(width 0.1)
				(type default)
			)
			(layer "F.Fab")
		)
		(pad "1" smd circle
			(at -0.40005 0 180)
			(size 0 0)
			(layers "F.Cu" "F.Mask" "F.Paste")
			(net "P12V_OCP_CB_2")
		)
		(pad "2" smd circle
			(at 0.40005 0 180)
			(size 0 0)
			(layers "F.Cu" "F.Mask" "F.Paste")
			(net "GND")
		)
	)
	(footprint ""
		(layer "F.Cu")
		(at 66.726054 -337.665314 90)
		(property "Reference" "PC400"
			(at 0 0 90)
			(layer "F.SilkS")
			(hide yes)
			(effects
				(font
					(size 1.27 1.27)
				)
			)
		)
		(property "Value" ""
			(at 0 0 90)
			(layer "F.Fab")
			(effects
				(font
					(size 1.27 1.27)
				)
			)
		)
		(duplicate_pad_numbers_are_jumpers no)
		(fp_line
			(start 0.7874 -0.4064)
			(end 0.7874 0.4064)
			(stroke
				(width 0.1524)
				(type default)
			)
			(layer "F.SilkS")
		)
		(fp_line
			(start -0.7874 -0.4064)
			(end 0.7874 -0.4064)
			(stroke
				(width 0.1524)
				(type default)
			)
			(layer "F.SilkS")
		)
		(fp_line
			(start 0.7874 0.4064)
			(end 0.408686 0.4064)
			(stroke
				(width 0.1524)
				(type default)
			)
			(layer "F.SilkS")
		)
		(fp_line
			(start -0.226314 0.4064)
			(end -0.7874 0.4064)
			(stroke
				(width 0.1524)
				(type default)
			)
			(layer "F.SilkS")
		)
		(fp_line
			(start -0.7874 0.4064)
			(end -0.7874 -0.4064)
			(stroke
				(width 0.1524)
				(type default)
			)
			(layer "F.SilkS")
		)
		(fp_line
			(start -0.12065 -0.305054)
			(end -0.12065 -0.2794)
			(stroke
				(width 0.1)
				(type default)
			)
			(layer "F.Fab")
		)
		(fp_line
			(start -0.67945 -0.305054)
			(end -0.12065 -0.305054)
			(stroke
				(width 0.1)
				(type default)
			)
			(layer "F.Fab")
		)
		(fp_line
			(start 0.67945 -0.3048)
			(end 0.67945 0.3048)
			(stroke
				(width 0.1)
				(type default)
			)
			(layer "F.Fab")
		)
		(fp_line
			(start 0.12065 -0.3048)
			(end 0.67945 -0.3048)
			(stroke
				(width 0.1)
				(type default)
			)
			(layer "F.Fab")
		)
		(fp_line
			(start 0.12065 -0.2794)
			(end 0.12065 -0.3048)
			(stroke
				(width 0.1)
				(type default)
			)
			(layer "F.Fab")
		)
		(fp_line
			(start -0.12065 -0.2794)
			(end 0.12065 -0.2794)
			(stroke
				(width 0.1)
				(type default)
			)
			(layer "F.Fab")
		)
		(fp_line
			(start 0.120396 0.2794)
			(end -0.12065 0.2794)
			(stroke
				(width 0.1)
				(type default)
			)
			(layer "F.Fab")
		)
		(fp_line
			(start -0.12065 0.2794)
			(end -0.12065 0.3048)
			(stroke
				(width 0.1)
				(type default)
			)
			(layer "F.Fab")
		)
		(fp_line
			(start 0.67945 0.3048)
			(end 0.120396 0.3048)
			(stroke
				(width 0.1)
				(type default)
			)
			(layer "F.Fab")
		)
		(fp_line
			(start 0.120396 0.3048)
			(end 0.120396 0.2794)
			(stroke
				(width 0.1)
				(type default)
			)
			(layer "F.Fab")
		)
		(fp_line
			(start -0.12065 0.3048)
			(end -0.67945 0.3048)
			(stroke
				(width 0.1)
				(type default)
			)
			(layer "F.Fab")
		)
		(fp_line
			(start -0.67945 0.3048)
			(end -0.67945 -0.305054)
			(stroke
				(width 0.1)
				(type default)
			)
			(layer "F.Fab")
		)
		(pad "1" smd circle
			(at -0.40005 0 90)
			(size 0 0)
			(layers "F.Cu" "F.Mask" "F.Paste")
			(net "PVDDCR_CPU1_P1_VCC3")
		)
		(pad "2" smd circle
			(at 0.40005 0 90)
			(size 0 0)
			(layers "F.Cu" "F.Mask" "F.Paste")
			(net "GND")
		)
	)
)
